# T6G (Grand Teton) — schematic netlist excerpt (pin names and nets, part order shuffled) for the footprints in the layout excerpt that follows; sources: Cadence DE-HDL packaged netlist, KiCad conversion of 04192023_DAF0TMB3IC0_F0TG_MB_C_brd_V02_OCP.brd

R2424  Q_RES  33.2 1% CHIP  pkg 0402LF  page 150 : A = SMB_PMBUS_3V3AUX_SDA ; B = SMB_PMBUS_3V3AUX_SDA_R0
R6785  Q_RES  0 5% CHIP  pkg 0402LF  page 151 : A = SMB_MUX_RT_R1_SDA ; B = SMB_SML1_PMBUS_HSC_SDA

(kicad_pcb
	(version 20260206)
	(generator "pcbnew")
	(generator_version "10.0")
	(general
		(thickness 1.6)
		(legacy_teardrops no)
	)
	(paper "A4")
	(title_block
		(title "04192023_DAF0TMB3IC0_F0TG_MB_C_brd_V02_OCP.brd")
		(comment 1 "Grand Teton / footprints 5958-5959 of 8354")
	)
	(layers
		(0 "F.Cu" signal "TOP")
		(4 "In1.Cu" signal "GND")
		(6 "In2.Cu" signal "IN1")
		(8 "In3.Cu" signal "GND1")
		(10 "In4.Cu" signal "IN2")
		(12 "In5.Cu" signal "GND2")
		(14 "In6.Cu" signal "IN3")
		(16 "In7.Cu" signal "GND3")
		(18 "In8.Cu" signal "VCC")
		(20 "In9.Cu" signal "VCC1")
		(22 "In10.Cu" signal "GND4")
		(24 "In11.Cu" signal "IN4")
		(26 "In12.Cu" signal "GND5")
		(28 "In13.Cu" signal "IN5")
		(30 "In14.Cu" signal "GND6")
		(32 "In15.Cu" signal "IN6")
		(34 "In16.Cu" signal "GND7")
		(2 "B.Cu" signal "BOTTOM")
		(9 "F.Adhes" user "F.Adhesive")
		(11 "B.Adhes" user "B.Adhesive")
		(13 "F.Paste" user "Package Geometry/Pastemask Top")
		(15 "B.Paste" user "Package Geometry/Pastemask Bottom")
		(5 "F.SilkS" user "Ref Des/Silkscreen Top")
		(7 "B.SilkS" user "Ref Des/Silkscreen Bottom")
		(1 "F.Mask" user "Board Geometry/Soldermask Top")
		(3 "B.Mask" user "Board Geometry/Soldermask Bottom")
		(17 "Dwgs.User" user "User.Drawings")
		(19 "Cmts.User" user "User.Comments")
		(21 "Eco1.User" user "User.Eco1")
		(23 "Eco2.User" user "User.Eco2")
		(25 "Edge.Cuts" user "Board Geometry/Outline")
		(27 "Margin" user)
		(31 "F.CrtYd" user "Package Geometry/Place Bound Top")
		(29 "B.CrtYd" user "Package Geometry/Place Bound Bottom")
		(35 "F.Fab" user "Ref Des/Assembly Top")
		(33 "B.Fab" user "Ref Des/Assembly Bottom")
	)
	(footprint ""
		(layer "B.Cu")
		(at 163.886388 -13.65504 90)
		(property "Reference" "R2424"
			(at 0 0 90)
			(layer "B.SilkS")
			(hide yes)
			(effects
				(font
					(size 1.27 1.27)
				)
				(justify mirror)
			)
		)
		(property "Value" ""
			(at 0 0 90)
			(layer "B.Fab")
			(effects
				(font
					(size 1.27 1.27)
				)
				(justify mirror)
			)
		)
		(duplicate_pad_numbers_are_jumpers no)
		(fp_line
			(start 0.7874 -0.4064)
			(end -0.7874 -0.4064)
			(stroke
				(width 0.1524)
				(type default)
			)
			(layer "B.SilkS")
		)
		(fp_line
			(start -0.7874 -0.4064)
			(end -0.7874 0.4064)
			(stroke
				(width 0.1524)
				(type default)
			)
			(layer "B.SilkS")
		)
		(fp_line
			(start 0.7874 0.4064)
			(end 0.7874 -0.4064)
			(stroke
				(width 0.1524)
				(type default)
			)
			(layer "B.SilkS")
		)
		(fp_line
			(start -0.7874 0.4064)
			(end 0.7874 0.4064)
			(stroke
				(width 0.1524)
				(type default)
			)
			(layer "B.SilkS")
		)
		(fp_line
			(start 0.67945 -0.305054)
			(end 0.12065 -0.305054)
			(stroke
				(width 0.1)
				(type default)
			)
			(layer "B.Fab")
		)
		(fp_line
			(start 0.12065 -0.305054)
			(end 0.12065 -0.2794)
			(stroke
				(width 0.1)
				(type default)
			)
			(layer "B.Fab")
		)
		(fp_line
			(start -0.12065 -0.3048)
			(end -0.67945 -0.3048)
			(stroke
				(width 0.1)
				(type default)
			)
			(layer "B.Fab")
		)
		(fp_line
			(start -0.67945 -0.3048)
			(end -0.67945 0.3048)
			(stroke
				(width 0.1)
				(type default)
			)
			(layer "B.Fab")
		)
		(fp_line
			(start 0.12065 -0.2794)
			(end -0.12065 -0.2794)
			(stroke
				(width 0.1)
				(type default)
			)
			(layer "B.Fab")
		)
		(fp_line
			(start -0.12065 -0.2794)
			(end -0.12065 -0.3048)
			(stroke
				(width 0.1)
				(type default)
			)
			(layer "B.Fab")
		)
		(fp_line
			(start 0.12065 0.2794)
			(end 0.12065 0.3048)
			(stroke
				(width 0.1)
				(type default)
			)
			(layer "B.Fab")
		)
		(fp_line
			(start -0.120396 0.2794)
			(end 0.12065 0.2794)
			(stroke
				(width 0.1)
				(type default)
			)
			(layer "B.Fab")
		)
		(fp_line
			(start 0.67945 0.3048)
			(end 0.67945 -0.305054)
			(stroke
				(width 0.1)
				(type default)
			)
			(layer "B.Fab")
		)
		(fp_line
			(start 0.12065 0.3048)
			(end 0.67945 0.3048)
			(stroke
				(width 0.1)
				(type default)
			)
			(layer "B.Fab")
		)
		(fp_line
			(start -0.120396 0.3048)
			(end -0.120396 0.2794)
			(stroke
				(width 0.1)
				(type default)
			)
			(layer "B.Fab")
		)
		(fp_line
			(start -0.67945 0.3048)
			(end -0.120396 0.3048)
			(stroke
				(width 0.1)
				(type default)
			)
			(layer "B.Fab")
		)
		(pad "1" smd circle
			(at 0.40005 0 270)
			(size 0 0)
			(layers "B.Cu" "B.Mask" "B.Paste")
			(net "SMB_PMBUS_3V3AUX_SDA")
		)
		(pad "2" smd circle
			(at -0.40005 0 270)
			(size 0 0)
			(layers "B.Cu" "B.Mask" "B.Paste")
			(net "SMB_PMBUS_3V3AUX_SDA_R0")
		)
	)
	(footprint ""
		(layer "B.Cu")
		(at 233.68 -330.708 180)
		(property "Reference" "R6785"
			(at 0 0 0)
			(layer "B.SilkS")
			(hide yes)
			(effects
				(font
					(size 1.27 1.27)
				)
				(justify mirror)
			)
		)
		(property "Value" ""
			(at 0 0 0)
			(layer "B.Fab")
			(effects
				(font
					(size 1.27 1.27)
				)
				(justify mirror)
			)
		)
		(duplicate_pad_numbers_are_jumpers no)
		(fp_line
			(start 0.7874 0.4064)
			(end 0.7874 -0.4064)
			(stroke
				(width 0.1524)
				(type default)
			)
			(layer "B.SilkS")
		)
		(fp_line
			(start 0.7874 -0.4064)
			(end -0.7874 -0.4064)
			(stroke
				(width 0.1524)
				(type default)
			)
			(layer "B.SilkS")
		)
		(fp_line
			(start -0.7874 0.4064)
			(end 0.7874 0.4064)
			(stroke
				(width 0.1524)
				(type default)
			)
			(layer "B.SilkS")
		)
		(fp_line
			(start -0.7874 -0.4064)
			(end -0.7874 0.4064)
			(stroke
				(width 0.1524)
				(type default)
			)
			(layer "B.SilkS")
		)
		(fp_line
			(start 0.67945 0.3048)
			(end 0.67945 -0.305054)
			(stroke
				(width 0.1)
				(type default)
			)
			(layer "B.Fab")
		)
		(fp_line
			(start 0.67945 -0.305054)
			(end 0.12065 -0.305054)
			(stroke
				(width 0.1)
				(type default)
			)
			(layer "B.Fab")
		)
		(fp_line
			(start 0.12065 0.3048)
			(end 0.67945 0.3048)
			(stroke
				(width 0.1)
				(type default)
			)
			(layer "B.Fab")
		)
		(fp_line
			(start 0.12065 0.2794)
			(end 0.12065 0.3048)
			(stroke
				(width 0.1)
				(type default)
			)
			(layer "B.Fab")
		)
		(fp_line
			(start 0.12065 -0.2794)
			(end -0.12065 -0.2794)
			(stroke
				(width 0.1)
				(type default)
			)
			(layer "B.Fab")
		)
		(fp_line
			(start 0.12065 -0.305054)
			(end 0.12065 -0.2794)
			(stroke
				(width 0.1)
				(type default)
			)
			(layer "B.Fab")
		)
		(fp_line
			(start -0.120396 0.3048)
			(end -0.120396 0.2794)
			(stroke
				(width 0.1)
				(type default)
			)
			(layer "B.Fab")
		)
		(fp_line
			(start -0.120396 0.2794)
			(end 0.12065 0.2794)
			(stroke
				(width 0.1)
				(type default)
			)
			(layer "B.Fab")
		)
		(fp_line
			(start -0.12065 -0.2794)
			(end -0.12065 -0.3048)
			(stroke
				(width 0.1)
				(type default)
			)
			(layer "B.Fab")
		)
		(fp_line
			(start -0.12065 -0.3048)
			(end -0.67945 -0.3048)
			(stroke
				(width 0.1)
				(type default)
			)
			(layer "B.Fab")
		)
		(fp_line
			(start -0.67945 0.3048)
			(end -0.120396 0.3048)
			(stroke
				(width 0.1)
				(type default)
			)
			(layer "B.Fab")
		)
		(fp_line
			(start -0.67945 -0.3048)
			(end -0.67945 0.3048)
			(stroke
				(width 0.1)
				(type default)
			)
			(layer "B.Fab")
		)
		(pad "1" smd circle
			(at 0.40005 0)
			(size 0 0)
			(layers "B.Cu" "B.Mask" "B.Paste")
			(net "SMB_MUX_RT_R1_SDA")
		)
		(pad "2" smd circle
			(at -0.40005 0)
			(size 0 0)
			(layers "B.Cu" "B.Mask" "B.Paste")
			(net "SMB_SML1_PMBUS_HSC_SDA")
		)
	)
)
